# S9S_MB_2U (Grand Teton) — schematic netlist excerpt (pin names and nets, part order shuffled) for the footprints in the layout excerpt that follows; sources: Cadence DE-HDL packaged netlist, KiCad conversion of 03242023_DA0F0TMBIJ0_F0T_Motherboard_J_brd_V01_OCP.brd

R2705  Q_RES  0 5% EMPTY  pkg 0402LF  page 234 : A = SMB_BMC_SWB_R_SCL ; B = SMB_BMC_SWB_BUF_R_SCL
C845  Q_CAP_DIFFBUS  DIFF BUS_0.22UF 6.3V 20% X6S  pkg C0201  page 174 : \1\ = P5E_CPU0_PE1_TX_C_DP<12> ; \2\ = P5E_CPU0_PE1_TX_DP<12>
R4306  Q_RES  0 5% CHIP  pkg 0402LF  page 179 : A = CLK_100M_PE_M2_0_R_DN ; B = CLK_100M_PE_M2_0_DN

(kicad_pcb
	(version 20260206)
	(generator "pcbnew")
	(generator_version "10.0")
	(general
		(thickness 1.6)
		(legacy_teardrops no)
	)
	(paper "A4")
	(title_block
		(title "03242023_DA0F0TMBIJ0_F0T_Motherboard_J_brd_V01_OCP.brd")
		(comment 1 "Grand Teton / footprints 681-683 of 6105")
	)
	(layers
		(0 "F.Cu" signal "TOP")
		(4 "In1.Cu" signal "GND")
		(6 "In2.Cu" signal "IN1")
		(8 "In3.Cu" signal "GND1")
		(10 "In4.Cu" signal "IN2")
		(12 "In5.Cu" signal "GND2")
		(14 "In6.Cu" signal "IN3")
		(16 "In7.Cu" signal "GND3")
		(18 "In8.Cu" signal "VCC")
		(20 "In9.Cu" signal "VCC1")
		(22 "In10.Cu" signal "GND4")
		(24 "In11.Cu" signal "IN4")
		(26 "In12.Cu" signal "GND5")
		(28 "In13.Cu" signal "IN5")
		(30 "In14.Cu" signal "GND6")
		(32 "In15.Cu" signal "IN6")
		(34 "In16.Cu" signal "GND7")
		(2 "B.Cu" signal "BOTTOM")
		(9 "F.Adhes" user "F.Adhesive")
		(11 "B.Adhes" user "B.Adhesive")
		(13 "F.Paste" user "Package Geometry/Pastemask Top")
		(15 "B.Paste" user "Package Geometry/Pastemask Bottom")
		(5 "F.SilkS" user "Ref Des/Silkscreen Top")
		(7 "B.SilkS" user "Ref Des/Silkscreen Bottom")
		(1 "F.Mask" user "Board Geometry/Soldermask Top")
		(3 "B.Mask" user "Board Geometry/Soldermask Bottom")
		(17 "Dwgs.User" user "User.Drawings")
		(19 "Cmts.User" user "User.Comments")
		(21 "Eco1.User" user "User.Eco1")
		(23 "Eco2.User" user "User.Eco2")
		(25 "Edge.Cuts" user "Board Geometry/Outline")
		(27 "Margin" user)
		(31 "F.CrtYd" user "Package Geometry/Place Bound Top")
		(29 "B.CrtYd" user "Package Geometry/Place Bound Bottom")
		(35 "F.Fab" user "Ref Des/Assembly Top")
		(33 "B.Fab" user "Ref Des/Assembly Bottom")
	)
	(footprint ""
		(layer "F.Cu")
		(at 332.115668 -76.153518 90)
		(property "Reference" "R4306"
			(at 0 0 90)
			(layer "F.SilkS")
			(hide yes)
			(effects
				(font
					(size 1.27 1.27)
				)
			)
		)
		(property "Value" ""
			(at 0 0 90)
			(layer "F.Fab")
			(effects
				(font
					(size 1.27 1.27)
				)
			)
		)
		(duplicate_pad_numbers_are_jumpers no)
		(fp_line
			(start 0.7874 -0.4064)
			(end 0.7874 0.4064)
			(stroke
				(width 0.1524)
				(type default)
			)
			(layer "F.SilkS")
		)
		(fp_line
			(start -0.7874 -0.4064)
			(end 0.7874 -0.4064)
			(stroke
				(width 0.1524)
				(type default)
			)
			(layer "F.SilkS")
		)
		(fp_line
			(start 0.7874 0.4064)
			(end -0.7874 0.4064)
			(stroke
				(width 0.1524)
				(type default)
			)
			(layer "F.SilkS")
		)
		(fp_line
			(start -0.7874 0.4064)
			(end -0.7874 -0.4064)
			(stroke
				(width 0.1524)
				(type default)
			)
			(layer "F.SilkS")
		)
		(fp_line
			(start -0.12065 -0.305054)
			(end -0.12065 -0.2794)
			(stroke
				(width 0.1)
				(type default)
			)
			(layer "F.Fab")
		)
		(fp_line
			(start -0.67945 -0.305054)
			(end -0.12065 -0.305054)
			(stroke
				(width 0.1)
				(type default)
			)
			(layer "F.Fab")
		)
		(fp_line
			(start 0.67945 -0.3048)
			(end 0.67945 0.3048)
			(stroke
				(width 0.1)
				(type default)
			)
			(layer "F.Fab")
		)
		(fp_line
			(start 0.12065 -0.3048)
			(end 0.67945 -0.3048)
			(stroke
				(width 0.1)
				(type default)
			)
			(layer "F.Fab")
		)
		(fp_line
			(start 0.12065 -0.2794)
			(end 0.12065 -0.3048)
			(stroke
				(width 0.1)
				(type default)
			)
			(layer "F.Fab")
		)
		(fp_line
			(start -0.12065 -0.2794)
			(end 0.12065 -0.2794)
			(stroke
				(width 0.1)
				(type default)
			)
			(layer "F.Fab")
		)
		(fp_line
			(start 0.120396 0.2794)
			(end -0.12065 0.2794)
			(stroke
				(width 0.1)
				(type default)
			)
			(layer "F.Fab")
		)
		(fp_line
			(start -0.12065 0.2794)
			(end -0.12065 0.3048)
			(stroke
				(width 0.1)
				(type default)
			)
			(layer "F.Fab")
		)
		(fp_line
			(start 0.67945 0.3048)
			(end 0.120396 0.3048)
			(stroke
				(width 0.1)
				(type default)
			)
			(layer "F.Fab")
		)
		(fp_line
			(start 0.120396 0.3048)
			(end 0.120396 0.2794)
			(stroke
				(width 0.1)
				(type default)
			)
			(layer "F.Fab")
		)
		(fp_line
			(start -0.12065 0.3048)
			(end -0.67945 0.3048)
			(stroke
				(width 0.1)
				(type default)
			)
			(layer "F.Fab")
		)
		(fp_line
			(start -0.67945 0.3048)
			(end -0.67945 -0.305054)
			(stroke
				(width 0.1)
				(type default)
			)
			(layer "F.Fab")
		)
		(pad "1" smd circle
			(at -0.40005 0 90)
			(size 0 0)
			(layers "F.Cu" "F.Mask" "F.Paste")
			(net "CLK_100M_PE_M2_0_R_DN")
		)
		(pad "2" smd circle
			(at 0.40005 0 90)
			(size 0 0)
			(layers "F.Cu" "F.Mask" "F.Paste")
			(net "CLK_100M_PE_M2_0_DN")
		)
	)
	(footprint ""
		(layer "F.Cu")
		(at 163.50615 -430.706276)
		(property "Reference" "R2705"
			(at 0 0 0)
			(layer "F.SilkS")
			(hide yes)
			(effects
				(font
					(size 1.27 1.27)
				)
			)
		)
		(property "Value" ""
			(at 0 0 0)
			(layer "F.Fab")
			(effects
				(font
					(size 1.27 1.27)
				)
			)
		)
		(duplicate_pad_numbers_are_jumpers no)
		(fp_line
			(start -0.7874 -0.4064)
			(end 0.7874 -0.4064)
			(stroke
				(width 0.1524)
				(type default)
			)
			(layer "F.SilkS")
		)
		(fp_line
			(start -0.7874 0.4064)
			(end -0.7874 -0.4064)
			(stroke
				(width 0.1524)
				(type default)
			)
			(layer "F.SilkS")
		)
		(fp_line
			(start 0.7874 -0.4064)
			(end 0.7874 0.4064)
			(stroke
				(width 0.1524)
				(type default)
			)
			(layer "F.SilkS")
		)
		(fp_line
			(start 0.7874 0.4064)
			(end -0.7874 0.4064)
			(stroke
				(width 0.1524)
				(type default)
			)
			(layer "F.SilkS")
		)
		(fp_line
			(start -0.67945 -0.305054)
			(end -0.12065 -0.305054)
			(stroke
				(width 0.1)
				(type default)
			)
			(layer "F.Fab")
		)
		(fp_line
			(start -0.67945 0.3048)
			(end -0.67945 -0.305054)
			(stroke
				(width 0.1)
				(type default)
			)
			(layer "F.Fab")
		)
		(fp_line
			(start -0.12065 -0.305054)
			(end -0.12065 -0.2794)
			(stroke
				(width 0.1)
				(type default)
			)
			(layer "F.Fab")
		)
		(fp_line
			(start -0.12065 -0.2794)
			(end 0.12065 -0.2794)
			(stroke
				(width 0.1)
				(type default)
			)
			(layer "F.Fab")
		)
		(fp_line
			(start -0.12065 0.2794)
			(end -0.12065 0.3048)
			(stroke
				(width 0.1)
				(type default)
			)
			(layer "F.Fab")
		)
		(fp_line
			(start -0.12065 0.3048)
			(end -0.67945 0.3048)
			(stroke
				(width 0.1)
				(type default)
			)
			(layer "F.Fab")
		)
		(fp_line
			(start 0.120396 0.2794)
			(end -0.12065 0.2794)
			(stroke
				(width 0.1)
				(type default)
			)
			(layer "F.Fab")
		)
		(fp_line
			(start 0.120396 0.3048)
			(end 0.120396 0.2794)
			(stroke
				(width 0.1)
				(type default)
			)
			(layer "F.Fab")
		)
		(fp_line
			(start 0.12065 -0.3048)
			(end 0.67945 -0.3048)
			(stroke
				(width 0.1)
				(type default)
			)
			(layer "F.Fab")
		)
		(fp_line
			(start 0.12065 -0.2794)
			(end 0.12065 -0.3048)
			(stroke
				(width 0.1)
				(type default)
			)
			(layer "F.Fab")
		)
		(fp_line
			(start 0.67945 -0.3048)
			(end 0.67945 0.3048)
			(stroke
				(width 0.1)
				(type default)
			)
			(layer "F.Fab")
		)
		(fp_line
			(start 0.67945 0.3048)
			(end 0.120396 0.3048)
			(stroke
				(width 0.1)
				(type default)
			)
			(layer "F.Fab")
		)
		(pad "1" smd circle
			(at -0.40005 0)
			(size 0 0)
			(layers "F.Cu" "F.Mask" "F.Paste")
			(net "SMB_BMC_SWB_R_SCL")
		)
		(pad "2" smd circle
			(at 0.40005 0)
			(size 0 0)
			(layers "F.Cu" "F.Mask" "F.Paste")
			(net "SMB_BMC_SWB_BUF_R_SCL")
		)
	)
	(footprint ""
		(layer "F.Cu")
		(at 399.312384 -17.612614 90)
		(property "Reference" "C845"
			(at 0 0 90)
			(layer "F.SilkS")
			(hide yes)
			(effects
				(font
					(size 1.27 1.27)
				)
			)
		)
		(property "Value" ""
			(at 0 0 90)
			(layer "F.Fab")
			(effects
				(font
					(size 1.27 1.27)
				)
			)
		)
		(duplicate_pad_numbers_are_jumpers no)
		(fp_line
			(start 0.299974 -0.150114)
			(end 0.299974 0.150114)
			(stroke
				(width 0.1)
				(type default)
			)
			(layer "F.Fab")
		)
		(fp_line
			(start -0.299974 -0.150114)
			(end 0.299974 -0.150114)
			(stroke
				(width 0.1)
				(type default)
			)
			(layer "F.Fab")
		)
		(fp_line
			(start 0.299974 0.150114)
			(end -0.299974 0.150114)
			(stroke
				(width 0.1)
				(type default)
			)
			(layer "F.Fab")
		)
		(fp_line
			(start -0.299974 0.150114)
			(end -0.299974 -0.150114)
			(stroke
				(width 0.1)
				(type default)
			)
			(layer "F.Fab")
		)
		(pad "1" smd rect
			(at -0.2667 0 90)
			(size 0.3048 0.381)
			(layers "F.Cu" "F.Mask" "F.Paste")
			(net "P5E_CPU0_PE1_TX_C_DP<12>")
		)
		(pad "2" smd rect
			(at 0.2667 0 90)
			(size 0.3048 0.381)
			(layers "F.Cu" "F.Mask" "F.Paste")
			(net "P5E_CPU0_PE1_TX_DP<12>")
		)
	)
)
